(kicad_pcb
	(version 20241229)
	(generator "pcbnew")
	(generator_version "9.0")
	(general
		(thickness 1.6296)
		(legacy_teardrops no)
	)
	(paper "A3")
	(title_block
		(title "Thunderbolt to 10GbE adapter")
		(date "2026-04-21")
		(rev "1.1.0")
		(company "Antmicro Ltd")
		(comment 1 "www.antmicro.com")
		(comment 9 "footprints 625-629 of 703")
	)
	(layers
		(0 "F.Cu" signal)
		(4 "In1.Cu" signal)
		(6 "In2.Cu" signal)
		(8 "In3.Cu" signal)
		(10 "In4.Cu" signal)
		(12 "In5.Cu" signal)
		(14 "In6.Cu" signal)
		(2 "B.Cu" signal)
		(9 "F.Adhes" user "F.Adhesive")
		(11 "B.Adhes" user "B.Adhesive")
		(13 "F.Paste" user)
		(15 "B.Paste" user)
		(5 "F.SilkS" user "F.Silkscreen")
		(7 "B.SilkS" user "B.Silkscreen")
		(1 "F.Mask" user)
		(3 "B.Mask" user)
		(17 "Dwgs.User" user "User.Drawings")
		(19 "Cmts.User" user "User.Comments")
		(21 "Eco1.User" user "User.Eco1")
		(23 "Eco2.User" user "User.Eco2")
		(25 "Edge.Cuts" user)
		(27 "Margin" user)
		(31 "F.CrtYd" user "F.Courtyard")
		(29 "B.CrtYd" user "B.Courtyard")
		(35 "F.Fab" user)
		(33 "B.Fab" user)
	)
	(footprint "antmicro-footprints:C_0402_1005Metric"
		(layer "B.Cu")
		(at 127.524999 123.950002 90)
		(descr "Capacitor SMD 0402")
		(tags "capacitor SMD 0402")
		(property "Reference" "C55"
			(at 7.700002 21.900002 270)
			(layer "B.SilkS")
			(effects
				(font
					(size 0.7 0.7)
					(thickness 0.15)
				)
				(justify mirror)
			)
		)
		(property "Value" "C_1u_0402"
			(at -1.022927 -2.155213 270)
			(layer "B.Fab")
			(effects
				(font
					(size 0.7 0.7)
					(thickness 0.15)
				)
				(justify left bottom mirror)
			)
		)
		(property "Datasheet" "https://product.tdk.com/en/search/capacitor/ceramic/mlcc/info?part_no=C1005X6S1A105K050BC"
			(at 0 0 270)
			(layer "B.Fab")
			(hide yes)
			(effects
				(font
					(size 1.27 1.27)
					(thickness 0.15)
				)
				(justify mirror)
			)
		)
		(property "Description" "SMD Multilayer Ceramic Capacitor, 1 µF, 10 V, 0402 [1005 Metric], ± 10%, X6S, C"
			(at 0 0 270)
			(layer "B.Fab")
			(hide yes)
			(effects
				(font
					(size 1.27 1.27)
					(thickness 0.15)
				)
				(justify mirror)
			)
		)
		(property "MPN" "C1005X6S1A105K050BC"
			(at 0 0 90)
			(unlocked yes)
			(layer "B.Fab")
			(hide yes)
			(effects
				(font
					(size 1 1)
					(thickness 0.15)
				)
				(justify mirror)
			)
		)
		(property "Manufacturer" "TDK"
			(at 0 0 90)
			(unlocked yes)
			(layer "B.Fab")
			(hide yes)
			(effects
				(font
					(size 1 1)
					(thickness 0.15)
				)
				(justify mirror)
			)
		)
		(property "License" "Apache-2.0"
			(at 0 0 90)
			(unlocked yes)
			(layer "B.Fab")
			(hide yes)
			(effects
				(font
					(size 1 1)
					(thickness 0.15)
				)
				(justify mirror)
			)
		)
		(property "Val" "1u"
			(at 0 0 90)
			(unlocked yes)
			(layer "B.Fab")
			(hide yes)
			(effects
				(font
					(size 1 1)
					(thickness 0.15)
				)
				(justify mirror)
			)
		)
		(property "Voltage" ""
			(at 0 0 90)
			(unlocked yes)
			(layer "B.Fab")
			(hide yes)
			(effects
				(font
					(size 1 1)
					(thickness 0.15)
				)
				(justify mirror)
			)
		)
		(property "Dielectric" ""
			(at 0 0 90)
			(unlocked yes)
			(layer "B.Fab")
			(hide yes)
			(effects
				(font
					(size 1 1)
					(thickness 0.15)
				)
				(justify mirror)
			)
		)
		(property "Author" "Antmicro"
			(at 0 0 90)
			(unlocked yes)
			(layer "B.Fab")
			(hide yes)
			(effects
				(font
					(size 1 1)
					(thickness 0.15)
				)
				(justify mirror)
			)
		)
		(sheetname "/TB Controller - Power/")
		(sheetfile "tb-power.kicad_sch")
		(attr smd)
		(fp_rect
			(start -0.925 0.47)
			(end 0.925 -0.47)
			(stroke
				(width 0.05)
				(type default)
			)
			(fill no)
			(layer "B.CrtYd")
		)
		(fp_line
			(start 0.504 -0.248)
			(end -0.494 -0.248)
			(stroke
				(width 0.15)
				(type solid)
			)
			(layer "B.Fab")
		)
		(fp_line
			(start -0.494 -0.248)
			(end -0.494 0.25)
			(stroke
				(width 0.15)
				(type solid)
			)
			(layer "B.Fab")
		)
		(fp_line
			(start 0.504 0.25)
			(end 0.504 -0.248)
			(stroke
				(width 0.15)
				(type solid)
			)
			(layer "B.Fab")
		)
		(fp_line
			(start -0.494 0.25)
			(end 0.504 0.25)
			(stroke
				(width 0.15)
				(type solid)
			)
			(layer "B.Fab")
		)
		(fp_text user "${REFERENCE}"
			(at -0.939 -4.599 270)
			(layer "B.Fab")
			(effects
				(font
					(size 0.7 0.7)
					(thickness 0.15)
				)
				(justify left bottom mirror)
			)
		)
		(fp_text user "License: Apache-2.0"
			(at -0.939 -5.799 270)
			(layer "B.Fab")
			(effects
				(font
					(size 0.7 0.7)
					(thickness 0.15)
				)
				(justify left bottom mirror)
			)
		)
		(fp_text user "Author: Antmicro"
			(at -0.939 -3.399 270)
			(layer "B.Fab")
			(effects
				(font
					(size 0.7 0.7)
					(thickness 0.15)
				)
				(justify left bottom mirror)
			)
		)
		(pad "1" smd roundrect
			(at -0.48 0 90)
			(size 0.59 0.64)
			(layers "B.Cu" "B.Mask" "B.Paste")
			(roundrect_rratio 0.25)
			(net 23 "GND")
			(pintype "passive")
		)
		(pad "2" smd roundrect
			(at 0.48 0 90)
			(size 0.59 0.64)
			(layers "B.Cu" "B.Mask" "B.Paste")
			(roundrect_rratio 0.25)
			(net 403 "Net-(C55-Pad2)")
			(pintype "passive")
		)
	)
	(footprint "antmicro-footprints:C_0402_1005Metric"
		(layer "B.Cu")
		(at 148.431866 87.935117 180)
		(descr "Capacitor SMD 0402")
		(tags "capacitor SMD 0402")
		(property "Reference" "C243"
			(at -17.975 -9.475 0)
			(layer "B.SilkS")
			(effects
				(font
					(size 0.7 0.7)
					(thickness 0.15)
				)
				(justify mirror)
			)
		)
		(property "Value" "C_1u_25V_0402"
			(at -1.022927 -2.155213 0)
			(layer "B.Fab")
			(effects
				(font
					(size 0.7 0.7)
					(thickness 0.15)
				)
				(justify left bottom mirror)
			)
		)
		(property "Datasheet" "https://www.murata.com/products/productdetail?partno=GRM155R61E105KE11%23"
			(at 0 0 0)
			(layer "B.Fab")
			(hide yes)
			(effects
				(font
					(size 1.27 1.27)
					(thickness 0.15)
				)
				(justify mirror)
			)
		)
		(property "Description" "SMD Multilayer Ceramic Capacitor, 1 µF, 25 V, 0402 [1005 Metric], ± 10%, X5R, GRM Series"
			(at 0 0 0)
			(layer "B.Fab")
			(hide yes)
			(effects
				(font
					(size 1.27 1.27)
					(thickness 0.15)
				)
				(justify mirror)
			)
		)
		(property "MPN" "GRM155R61E105KE11J"
			(at 0 0 180)
			(unlocked yes)
			(layer "B.Fab")
			(hide yes)
			(effects
				(font
					(size 1 1)
					(thickness 0.15)
				)
				(justify mirror)
			)
		)
		(property "Manufacturer" "Murata"
			(at 0 0 180)
			(unlocked yes)
			(layer "B.Fab")
			(hide yes)
			(effects
				(font
					(size 1 1)
					(thickness 0.15)
				)
				(justify mirror)
			)
		)
		(property "License" "Apache-2.0"
			(at 0 0 180)
			(unlocked yes)
			(layer "B.Fab")
			(hide yes)
			(effects
				(font
					(size 1 1)
					(thickness 0.15)
				)
				(justify mirror)
			)
		)
		(property "Author" "Antmicro"
			(at 0 0 180)
			(unlocked yes)
			(layer "B.Fab")
			(hide yes)
			(effects
				(font
					(size 1 1)
					(thickness 0.15)
				)
				(justify mirror)
			)
		)
		(property "Val" "1u"
			(at 0 0 180)
			(unlocked yes)
			(layer "B.Fab")
			(hide yes)
			(effects
				(font
					(size 1 1)
					(thickness 0.15)
				)
				(justify mirror)
			)
		)
		(property "Voltage" "25V"
			(at 0 0 180)
			(unlocked yes)
			(layer "B.Fab")
			(hide yes)
			(effects
				(font
					(size 1 1)
					(thickness 0.15)
				)
				(justify mirror)
			)
		)
		(property "Dielectric" "X5R"
			(at 0 0 180)
			(unlocked yes)
			(layer "B.Fab")
			(hide yes)
			(effects
				(font
					(size 1 1)
					(thickness 0.15)
				)
				(justify mirror)
			)
		)
		(sheetname "/X710-AT2 power/")
		(sheetfile "x710-at2-power.kicad_sch")
		(attr smd)
		(fp_rect
			(start -0.925 0.47)
			(end 0.925 -0.47)
			(stroke
				(width 0.05)
				(type default)
			)
			(fill no)
			(layer "B.CrtYd")
		)
		(fp_line
			(start 0.504 0.25)
			(end 0.504 -0.248)
			(stroke
				(width 0.15)
				(type solid)
			)
			(layer "B.Fab")
		)
		(fp_line
			(start 0.504 -0.248)
			(end -0.494 -0.248)
			(stroke
				(width 0.15)
				(type solid)
			)
			(layer "B.Fab")
		)
		(fp_line
			(start -0.494 0.25)
			(end 0.504 0.25)
			(stroke
				(width 0.15)
				(type solid)
			)
			(layer "B.Fab")
		)
		(fp_line
			(start -0.494 -0.248)
			(end -0.494 0.25)
			(stroke
				(width 0.15)
				(type solid)
			)
			(layer "B.Fab")
		)
		(fp_text user "License: Apache-2.0"
			(at -0.939 -5.799 0)
			(layer "B.Fab")
			(effects
				(font
					(size 0.7 0.7)
					(thickness 0.15)
				)
				(justify left bottom mirror)
			)
		)
		(fp_text user "${REFERENCE}"
			(at -0.939 -4.599 0)
			(layer "B.Fab")
			(effects
				(font
					(size 0.7 0.7)
					(thickness 0.15)
				)
				(justify left bottom mirror)
			)
		)
		(fp_text user "Author: Antmicro"
			(at -0.939 -3.399 0)
			(layer "B.Fab")
			(effects
				(font
					(size 0.7 0.7)
					(thickness 0.15)
				)
				(justify left bottom mirror)
			)
		)
		(pad "1" smd roundrect
			(at -0.48 0 180)
			(size 0.59 0.64)
			(layers "B.Cu" "B.Mask" "B.Paste")
			(roundrect_rratio 0.25)
			(net 23 "GND")
			(pintype "passive")
		)
		(pad "2" smd roundrect
			(at 0.48 0 180)
			(size 0.59 0.64)
			(layers "B.Cu" "B.Mask" "B.Paste")
			(roundrect_rratio 0.25)
			(net 7 "+3V3")
			(pintype "passive")
		)
	)
	(footprint "antmicro-footprints:C_0402_1005Metric"
		(layer "B.Cu")
		(at 182.05 133.25 180)
		(descr "Capacitor SMD 0402")
		(tags "capacitor SMD 0402")
		(property "Reference" "C301"
			(at -1.2 0.5 0)
			(layer "B.SilkS")
			(effects
				(font
					(size 0.7 0.7)
					(thickness 0.15)
				)
				(justify left bottom mirror)
			)
		)
		(property "Value" "C_1u_25V_0402"
			(at -1.022927 -2.155213 0)
			(layer "B.Fab")
			(effects
				(font
					(size 0.7 0.7)
					(thickness 0.15)
				)
				(justify left bottom mirror)
			)
		)
		(property "Datasheet" "https://www.murata.com/products/productdetail?partno=GRM155R61E105KE11%23"
			(at 0 0 0)
			(layer "B.Fab")
			(hide yes)
			(effects
				(font
					(size 1.27 1.27)
					(thickness 0.15)
				)
				(justify mirror)
			)
		)
		(property "Description" "SMD Multilayer Ceramic Capacitor, 1 µF, 25 V, 0402 [1005 Metric], ± 10%, X5R, GRM Series"
			(at 0 0 0)
			(layer "B.Fab")
			(hide yes)
			(effects
				(font
					(size 1.27 1.27)
					(thickness 0.15)
				)
				(justify mirror)
			)
		)
		(property "MPN" "GRM155R61E105KE11J"
			(at 0 0 180)
			(unlocked yes)
			(layer "B.Fab")
			(hide yes)
			(effects
				(font
					(size 1 1)
					(thickness 0.15)
				)
				(justify mirror)
			)
		)
		(property "Manufacturer" "Murata"
			(at 0 0 180)
			(unlocked yes)
			(layer "B.Fab")
			(hide yes)
			(effects
				(font
					(size 1 1)
					(thickness 0.15)
				)
				(justify mirror)
			)
		)
		(property "License" "Apache-2.0"
			(at 0 0 180)
			(unlocked yes)
			(layer "B.Fab")
			(hide yes)
			(effects
				(font
					(size 1 1)
					(thickness 0.15)
				)
				(justify mirror)
			)
		)
		(property "Author" "Antmicro"
			(at 0 0 180)
			(unlocked yes)
			(layer "B.Fab")
			(hide yes)
			(effects
				(font
					(size 1 1)
					(thickness 0.15)
				)
				(justify mirror)
			)
		)
		(property "Val" "1u"
			(at 0 0 180)
			(unlocked yes)
			(layer "B.Fab")
			(hide yes)
			(effects
				(font
					(size 1 1)
					(thickness 0.15)
				)
				(justify mirror)
			)
		)
		(property "Voltage" "25V"
			(at 0 0 180)
			(unlocked yes)
			(layer "B.Fab")
			(hide yes)
			(effects
				(font
					(size 1 1)
					(thickness 0.15)
				)
				(justify mirror)
			)
		)
		(property "Dielectric" "X5R"
			(at 0 0 180)
			(unlocked yes)
			(layer "B.Fab")
			(hide yes)
			(effects
				(font
					(size 1 1)
					(thickness 0.15)
				)
				(justify mirror)
			)
		)
		(sheetname "/2xRJ45/")
		(sheetfile "2xrj45.kicad_sch")
		(attr smd)
		(fp_rect
			(start -0.925 0.47)
			(end 0.925 -0.47)
			(stroke
				(width 0.05)
				(type default)
			)
			(fill no)
			(layer "B.CrtYd")
		)
		(fp_line
			(start 0.504 0.25)
			(end 0.504 -0.248)
			(stroke
				(width 0.15)
				(type solid)
			)
			(layer "B.Fab")
		)
		(fp_line
			(start 0.504 -0.248)
			(end -0.494 -0.248)
			(stroke
				(width 0.15)
				(type solid)
			)
			(layer "B.Fab")
		)
		(fp_line
			(start -0.494 0.25)
			(end 0.504 0.25)
			(stroke
				(width 0.15)
				(type solid)
			)
			(layer "B.Fab")
		)
		(fp_line
			(start -0.494 -0.248)
			(end -0.494 0.25)
			(stroke
				(width 0.15)
				(type solid)
			)
			(layer "B.Fab")
		)
		(fp_text user "Author: Antmicro"
			(at -0.939 -3.399 0)
			(layer "B.Fab")
			(effects
				(font
					(size 0.7 0.7)
					(thickness 0.15)
				)
				(justify left bottom mirror)
			)
		)
		(fp_text user "License: Apache-2.0"
			(at -0.939 -5.799 0)
			(layer "B.Fab")
			(effects
				(font
					(size 0.7 0.7)
					(thickness 0.15)
				)
				(justify left bottom mirror)
			)
		)
		(fp_text user "${REFERENCE}"
			(at -0.939 -4.599 0)
			(layer "B.Fab")
			(effects
				(font
					(size 0.7 0.7)
					(thickness 0.15)
				)
				(justify left bottom mirror)
			)
		)
		(pad "1" smd roundrect
			(at -0.48 0 180)
			(size 0.59 0.64)
			(layers "B.Cu" "B.Mask" "B.Paste")
			(roundrect_rratio 0.25)
			(net 23 "GND")
			(pintype "passive")
		)
		(pad "2" smd roundrect
			(at 0.48 0 180)
			(size 0.59 0.64)
			(layers "B.Cu" "B.Mask" "B.Paste")
			(roundrect_rratio 0.25)
			(net 134 "/2xRJ45/P1_CT")
			(pintype "passive")
		)
	)
	(footprint "antmicro-footprints:R_0402_1005Metric"
		(layer "B.Cu")
		(at 136.5 120.15)
		(descr "Resistor SMD 0402")
		(tags "resistor SMD 0402")
		(property "Reference" "R41"
			(at 19.525001 -7.450001 180)
			(layer "B.SilkS")
			(effects
				(font
					(size 0.7 0.7)
					(thickness 0.15)
				)
				(justify mirror)
			)
		)
		(property "Value" "R_100k_0402"
			(at -1.011843 -1.772047 180)
			(layer "B.Fab")
			(effects
				(font
					(size 0.7 0.7)
					(thickness 0.15)
				)
				(justify left bottom mirror)
			)
		)
		(property "Datasheet" "https://www.bourns.com/docs/product-datasheets/cr.pdf"
			(at 0 0 180)
			(layer "B.Fab")
			(hide yes)
			(effects
				(font
					(size 1.27 1.27)
					(thickness 0.15)
				)
				(justify mirror)
			)
		)
		(property "Description" "SMD Chip Resistor, 100 kohm, ± 1%, 62.5 mW, 0402 [1005 Metric], Thick Film, General Purpose"
			(at 0 0 180)
			(layer "B.Fab")
			(hide yes)
			(effects
				(font
					(size 1.27 1.27)
					(thickness 0.15)
				)
				(justify mirror)
			)
		)
		(property "MPN" "CR0402-FX-1003GLF"
			(at 0 0 0)
			(unlocked yes)
			(layer "B.Fab")
			(hide yes)
			(effects
				(font
					(size 1 1)
					(thickness 0.15)
				)
				(justify mirror)
			)
		)
		(property "Manufacturer" "Bourns"
			(at 0 0 0)
			(unlocked yes)
			(layer "B.Fab")
			(hide yes)
			(effects
				(font
					(size 1 1)
					(thickness 0.15)
				)
				(justify mirror)
			)
		)
		(property "License" "Apache-2.0"
			(at 0 0 0)
			(unlocked yes)
			(layer "B.Fab")
			(hide yes)
			(effects
				(font
					(size 1 1)
					(thickness 0.15)
				)
				(justify mirror)
			)
		)
		(property "Val" "100k"
			(at 0 0 0)
			(unlocked yes)
			(layer "B.Fab")
			(hide yes)
			(effects
				(font
					(size 1 1)
					(thickness 0.15)
				)
				(justify mirror)
			)
		)
		(property "Tolerance" "1%"
			(at 0 0 0)
			(unlocked yes)
			(layer "B.Fab")
			(hide yes)
			(effects
				(font
					(size 1 1)
					(thickness 0.15)
				)
				(justify mirror)
			)
		)
		(property "Author" "Antmicro"
			(at 0 0 0)
			(unlocked yes)
			(layer "B.Fab")
			(hide yes)
			(effects
				(font
					(size 1 1)
					(thickness 0.15)
				)
				(justify mirror)
			)
		)
		(sheetname "/TB Controller/")
		(sheetfile "tb.kicad_sch")
		(attr smd)
		(fp_rect
			(start -0.925 0.47)
			(end 0.925 -0.47)
			(stroke
				(width 0.05)
				(type default)
			)
			(fill no)
			(layer "B.CrtYd")
		)
		(fp_rect
			(start -0.5 0.25)
			(end 0.5 -0.25)
			(stroke
				(width 0.15)
				(type solid)
			)
			(fill no)
			(layer "B.Fab")
		)
		(fp_text user "${REFERENCE}"
			(at -0.95 -3.168 180)
			(layer "B.Fab")
			(effects
				(font
					(size 0.7 0.7)
					(thickness 0.15)
				)
				(justify left bottom mirror)
			)
		)
		(fp_text user "Author: Antmicro"
			(at -0.95 -4.169 180)
			(layer "B.Fab")
			(effects
				(font
					(size 0.7 0.7)
					(thickness 0.15)
				)
				(justify left bottom mirror)
			)
		)
		(fp_text user "License: Apache-2.0"
			(at -0.95 -5.169 180)
			(layer "B.Fab")
			(effects
				(font
					(size 0.7 0.7)
					(thickness 0.15)
				)
				(justify left bottom mirror)
			)
		)
		(pad "1" smd roundrect
			(at -0.48 0)
			(size 0.59 0.64)
			(layers "B.Cu" "B.Mask" "B.Paste")
			(roundrect_rratio 0.25)
			(net 184 "Net-(U4C-DPSRC_HPD)")
			(pintype "passive")
		)
		(pad "2" smd roundrect
			(at 0.48 0)
			(size 0.59 0.64)
			(layers "B.Cu" "B.Mask" "B.Paste")
			(roundrect_rratio 0.25)
			(net 23 "GND")
			(pintype "passive")
		)
	)
	(footprint "antmicro-footprints:R_0402_1005Metric"
		(layer "B.Cu")
		(at 148.425 85.925 180)
		(descr "Resistor SMD 0402")
		(tags "resistor SMD 0402")
		(property "Reference" "R180"
			(at -17.975 -9.475 0)
			(layer "B.SilkS")
			(effects
				(font
					(size 0.7 0.7)
					(thickness 0.15)
				)
				(justify mirror)
			)
		)
		(property "Value" "R_10k_0402"
			(at -1.011843 -1.772047 0)
			(layer "B.Fab")
			(effects
				(font
					(size 0.7 0.7)
					(thickness 0.15)
				)
				(justify left bottom mirror)
			)
		)
		(property "Datasheet" "https://www.bourns.com/docs/product-datasheets/cr.pdf"
			(at 0 0 0)
			(layer "B.Fab")
			(hide yes)
			(effects
				(font
					(size 1.27 1.27)
					(thickness 0.15)
				)
				(justify mirror)
			)
		)
		(property "Description" "SMD Chip Resistor, 10 kohm, ± 1%, 62.5 mW, 0402 [1005 Metric], Thick Film, General Purpose"
			(at 0 0 0)
			(layer "B.Fab")
			(hide yes)
			(effects
				(font
					(size 1.27 1.27)
					(thickness 0.15)
				)
				(justify mirror)
			)
		)
		(property "MPN" "CR0402-FX-1002GLF"
			(at 0 0 180)
			(unlocked yes)
			(layer "B.Fab")
			(hide yes)
			(effects
				(font
					(size 1 1)
					(thickness 0.15)
				)
				(justify mirror)
			)
		)
		(property "Manufacturer" "Bourns"
			(at 0 0 180)
			(unlocked yes)
			(layer "B.Fab")
			(hide yes)
			(effects
				(font
					(size 1 1)
					(thickness 0.15)
				)
				(justify mirror)
			)
		)
		(property "License" "Apache-2.0"
			(at 0 0 180)
			(unlocked yes)
			(layer "B.Fab")
			(hide yes)
			(effects
				(font
					(size 1 1)
					(thickness 0.15)
				)
				(justify mirror)
			)
		)
		(property "Author" "Antmicro"
			(at 0 0 180)
			(unlocked yes)
			(layer "B.Fab")
			(hide yes)
			(effects
				(font
					(size 1 1)
					(thickness 0.15)
				)
				(justify mirror)
			)
		)
		(property "Val" "10k"
			(at 0 0 180)
			(unlocked yes)
			(layer "B.Fab")
			(hide yes)
			(effects
				(font
					(size 1 1)
					(thickness 0.15)
				)
				(justify mirror)
			)
		)
		(property "Tolerance" "1%"
			(at 0 0 180)
			(unlocked yes)
			(layer "B.Fab")
			(hide yes)
			(effects
				(font
					(size 1 1)
					(thickness 0.15)
				)
				(justify mirror)
			)
		)
		(sheetname "/X710-AT2 Misc/")
		(sheetfile "x710-at2-mics.kicad_sch")
		(attr smd)
		(fp_rect
			(start -0.925 0.47)
			(end 0.925 -0.47)
			(stroke
				(width 0.05)
				(type default)
			)
			(fill no)
			(layer "B.CrtYd")
		)
		(fp_rect
			(start -0.5 0.25)
			(end 0.5 -0.25)
			(stroke
				(width 0.15)
				(type solid)
			)
			(fill no)
			(layer "B.Fab")
		)
		(fp_text user "Author: Antmicro"
			(at -0.95 -4.169 0)
			(layer "B.Fab")
			(effects
				(font
					(size 0.7 0.7)
					(thickness 0.15)
				)
				(justify left bottom mirror)
			)
		)
		(fp_text user "${REFERENCE}"
			(at -0.95 -3.168 0)
			(layer "B.Fab")
			(effects
				(font
					(size 0.7 0.7)
					(thickness 0.15)
				)
				(justify left bottom mirror)
			)
		)
		(fp_text user "License: Apache-2.0"
			(at -0.95 -5.169 0)
			(layer "B.Fab")
			(effects
				(font
					(size 0.7 0.7)
					(thickness 0.15)
				)
				(justify left bottom mirror)
			)
		)
		(pad "1" smd roundrect
			(at -0.48 0 180)
			(size 0.59 0.64)
			(layers "B.Cu" "B.Mask" "B.Paste")
			(roundrect_rratio 0.25)
			(net 445 "Net-(U14D-SMBD)")
			(pintype "passive")
		)
		(pad "2" smd roundrect
			(at 0.48 0 180)
			(size 0.59 0.64)
			(layers "B.Cu" "B.Mask" "B.Paste")
			(roundrect_rratio 0.25)
			(net 7 "+3V3")
			(pintype "passive")
		)
	)
)
